# BASEBOARD_FAB2 (Tioga Pass) — schematic netlist excerpt (pin names and nets, part order shuffled) for the footprints in the layout excerpt that follows; sources: Cadence DE-HDL packaged netlist, KiCad conversion of Wiwynn_Tioga_Pass_MB.brd

R1E4  RES  100.0 1% CHIP  pkg 0402  page 209 : A = VSENSE_PVCCIN_CPU1_P ; B = PVCCIN_CPU1
C2L47  CAP_A  0.01UF 25V 10% X7R  pkg 0402V  page 173 : A = SATA6G_P4_TX_C_DP ; B = SATA6G_PCH_PCIE_UP_SATA_TXP<4>
C3M11  CAP  0.22UF 16V 10% X7R  pkg 0402  page 105 : A = P3E_CPU0_PE1_PCH_R_RXP<14> ; B = P3E_CPU0_PE1_PCH_RXP<14>

(kicad_pcb
	(version 20260206)
	(generator "pcbnew")
	(generator_version "10.0")
	(general
		(thickness 1.6)
		(legacy_teardrops no)
	)
	(paper "A4")
	(title_block
		(title "Wiwynn_Tioga_Pass_MB.brd")
		(comment 1 "Tioga Pass / footprints 2434-2436 of 4770")
	)
	(layers
		(0 "F.Cu" signal "TOP")
		(4 "In1.Cu" signal "L2GND")
		(6 "In2.Cu" signal "L3")
		(8 "In3.Cu" signal "L4GND")
		(10 "In4.Cu" signal "L5")
		(12 "In5.Cu" signal "L6GND")
		(14 "In6.Cu" signal "L7VCC")
		(16 "In7.Cu" signal "L8VCC")
		(18 "In8.Cu" signal "L9GND")
		(20 "In9.Cu" signal "L10")
		(22 "In10.Cu" signal "L11GND")
		(24 "In11.Cu" signal "L12")
		(26 "In12.Cu" signal "L13GND")
		(2 "B.Cu" signal "BOTTOM")
		(9 "F.Adhes" user "F.Adhesive")
		(11 "B.Adhes" user "B.Adhesive")
		(13 "F.Paste" user "Package Geometry/Pastemask Top")
		(15 "B.Paste" user "Package Geometry/Pastemask Bottom")
		(5 "F.SilkS" user "Ref Des/Silkscreen Top")
		(7 "B.SilkS" user "Ref Des/Silkscreen Bottom")
		(1 "F.Mask" user "Board Geometry/Soldermask Top")
		(3 "B.Mask" user "Board Geometry/Soldermask Bottom")
		(17 "Dwgs.User" user "User.Drawings")
		(19 "Cmts.User" user "User.Comments")
		(21 "Eco1.User" user "User.Eco1")
		(23 "Eco2.User" user "User.Eco2")
		(25 "Edge.Cuts" user "Board Geometry/Outline")
		(27 "Margin" user)
		(31 "F.CrtYd" user "Package Geometry/Place Bound Top")
		(29 "B.CrtYd" user "Package Geometry/Place Bound Bottom")
		(35 "F.Fab" user "Ref Des/Assembly Top")
		(33 "B.Fab" user "Ref Des/Assembly Bottom")
	)
	(footprint ""
		(layer "B.Cu")
		(at 414.5534 -141.0208 -90)
		(property "Reference" "C2L47"
			(at 0 0 90)
			(layer "B.SilkS")
			(hide yes)
			(effects
				(font
					(size 1.27 1.27)
				)
				(justify mirror)
			)
		)
		(property "Value" ""
			(at 0 0 90)
			(layer "B.Fab")
			(effects
				(font
					(size 1.27 1.27)
				)
				(justify mirror)
			)
		)
		(duplicate_pad_numbers_are_jumpers no)
		(fp_poly
			(pts
				(xy -0.3048 -0.1016) (xy -0.3048 0.9906) (xy 0.3048 0.9906) (xy 0.3048 -0.1016)
			)
			(stroke
				(width 0)
				(type default)
			)
			(fill no)
			(layer "B.CrtYd")
		)
		(fp_line
			(start -0.3048 0.9906)
			(end -0.3048 -0.1016)
			(stroke
				(width 0.1)
				(type default)
			)
			(layer "B.Fab")
		)
		(fp_line
			(start 0.3048 0.9906)
			(end -0.3048 0.9906)
			(stroke
				(width 0.1)
				(type default)
			)
			(layer "B.Fab")
		)
		(fp_line
			(start -0.3048 -0.1016)
			(end 0.3048 -0.1016)
			(stroke
				(width 0.1)
				(type default)
			)
			(layer "B.Fab")
		)
		(fp_line
			(start 0.3048 -0.1016)
			(end 0.3048 0.9906)
			(stroke
				(width 0.1)
				(type default)
			)
			(layer "B.Fab")
		)
		(pad "1" smd rect
			(at 0 0 90)
			(size 0.508 0.508)
			(layers "B.Cu" "B.Mask" "B.Paste")
			(net "SATA6G_P4_TX_C_DP")
		)
		(pad "2" smd rect
			(at 0 0.889 90)
			(size 0.508 0.508)
			(layers "B.Cu" "B.Mask" "B.Paste")
			(net "SATA6G_PCH_PCIE_UP_SATA_TXP<4>")
		)
		(zone
			(layer "B.Cu")
			(hatch none 0.5)
			(connect_pads
				(clearance 0)
			)
			(min_thickness 0.25)
			(keepout
				(tracks not_allowed)
				(vias allowed)
				(pads allowed)
				(copperpour not_allowed)
				(footprints allowed)
			)
			(placement
				(enabled no)
				(sheetname "")
			)
			(fill
				(thermal_gap 0.5)
				(thermal_bridge_width 0.5)
				(island_removal_mode 0)
			)
			(polygon
				(pts
					(xy 413.9184 -140.7668) (xy 413.9184 -141.2748) (xy 414.2994 -141.2748) (xy 414.2994 -140.7668)
				)
			)
		)
		(zone
			(layer "B.Cu")
			(hatch none 0.5)
			(connect_pads
				(clearance 0)
			)
			(min_thickness 0.25)
			(keepout
				(tracks allowed)
				(vias not_allowed)
				(pads allowed)
				(copperpour not_allowed)
				(footprints allowed)
			)
			(placement
				(enabled no)
				(sheetname "")
			)
			(fill
				(thermal_gap 0.5)
				(thermal_bridge_width 0.5)
				(island_removal_mode 0)
			)
			(polygon
				(pts
					(xy 414.2994 -140.7668) (xy 414.2994 -141.2748) (xy 413.9184 -141.2748) (xy 413.9184 -140.7668)
				)
			)
		)
	)
	(footprint ""
		(layer "B.Cu")
		(at 63.246 -64.7954 180)
		(property "Reference" "R1E4"
			(at 0 0 0)
			(layer "B.SilkS")
			(hide yes)
			(effects
				(font
					(size 1.27 1.27)
				)
				(justify mirror)
			)
		)
		(property "Value" ""
			(at 0 0 0)
			(layer "B.Fab")
			(effects
				(font
					(size 1.27 1.27)
				)
				(justify mirror)
			)
		)
		(duplicate_pad_numbers_are_jumpers no)
		(fp_poly
			(pts
				(xy 0.2794 -0.1016) (xy -0.2794 -0.1016) (xy -0.2794 0.9906) (xy 0.2794 0.9906)
			)
			(stroke
				(width 0)
				(type default)
			)
			(fill no)
			(layer "B.CrtYd")
		)
		(fp_line
			(start 0.2794 0.9906)
			(end -0.2794 0.9906)
			(stroke
				(width 0.1)
				(type default)
			)
			(layer "B.Fab")
		)
		(fp_line
			(start 0.2794 -0.1016)
			(end 0.2794 0.9906)
			(stroke
				(width 0.1)
				(type default)
			)
			(layer "B.Fab")
		)
		(fp_line
			(start -0.2794 0.9906)
			(end -0.2794 -0.1016)
			(stroke
				(width 0.1)
				(type default)
			)
			(layer "B.Fab")
		)
		(fp_line
			(start -0.2794 -0.1016)
			(end 0.2794 -0.1016)
			(stroke
				(width 0.1)
				(type default)
			)
			(layer "B.Fab")
		)
		(pad "1" smd rect
			(at 0 0)
			(size 0.508 0.508)
			(layers "B.Cu" "B.Mask" "B.Paste")
			(net "VSENSE_PVCCIN_CPU1_P")
		)
		(pad "2" smd rect
			(at 0 0.889)
			(size 0.508 0.508)
			(layers "B.Cu" "B.Mask" "B.Paste")
			(net "PVCCIN_CPU1")
		)
		(zone
			(layer "B.Cu")
			(hatch none 0.5)
			(connect_pads
				(clearance 0)
			)
			(min_thickness 0.25)
			(keepout
				(tracks not_allowed)
				(vias allowed)
				(pads allowed)
				(copperpour not_allowed)
				(footprints allowed)
			)
			(placement
				(enabled no)
				(sheetname "")
			)
			(fill
				(thermal_gap 0.5)
				(thermal_bridge_width 0.5)
				(island_removal_mode 0)
			)
			(polygon
				(pts
					(xy 62.992 -65.4304) (xy 63.5 -65.4304) (xy 63.5 -65.0494) (xy 62.992 -65.0494)
				)
			)
		)
		(zone
			(layer "B.Cu")
			(hatch none 0.5)
			(connect_pads
				(clearance 0)
			)
			(min_thickness 0.25)
			(keepout
				(tracks allowed)
				(vias not_allowed)
				(pads allowed)
				(copperpour not_allowed)
				(footprints allowed)
			)
			(placement
				(enabled no)
				(sheetname "")
			)
			(fill
				(thermal_gap 0.5)
				(thermal_bridge_width 0.5)
				(island_removal_mode 0)
			)
			(polygon
				(pts
					(xy 62.992 -65.0494) (xy 63.5 -65.0494) (xy 63.5 -65.4304) (xy 62.992 -65.4304)
				)
			)
		)
	)
	(footprint ""
		(layer "B.Cu")
		(at 350.022414 -126.345442 -90)
		(property "Reference" "C3M11"
			(at 0 0 90)
			(layer "B.SilkS")
			(hide yes)
			(effects
				(font
					(size 1.27 1.27)
				)
				(justify mirror)
			)
		)
		(property "Value" ""
			(at 0 0 90)
			(layer "B.Fab")
			(effects
				(font
					(size 1.27 1.27)
				)
				(justify mirror)
			)
		)
		(duplicate_pad_numbers_are_jumpers no)
		(fp_poly
			(pts
				(xy -0.3048 -0.1016) (xy -0.3048 0.9906) (xy 0.3048 0.9906) (xy 0.3048 -0.1016)
			)
			(stroke
				(width 0)
				(type default)
			)
			(fill no)
			(layer "B.CrtYd")
		)
		(fp_line
			(start -0.3048 0.9906)
			(end -0.3048 -0.1016)
			(stroke
				(width 0.1)
				(type default)
			)
			(layer "B.Fab")
		)
		(fp_line
			(start 0.3048 0.9906)
			(end -0.3048 0.9906)
			(stroke
				(width 0.1)
				(type default)
			)
			(layer "B.Fab")
		)
		(fp_line
			(start -0.3048 -0.1016)
			(end 0.3048 -0.1016)
			(stroke
				(width 0.1)
				(type default)
			)
			(layer "B.Fab")
		)
		(fp_line
			(start 0.3048 -0.1016)
			(end 0.3048 0.9906)
			(stroke
				(width 0.1)
				(type default)
			)
			(layer "B.Fab")
		)
		(pad "1" smd rect
			(at 0 0 90)
			(size 0.508 0.508)
			(layers "B.Cu" "B.Mask" "B.Paste")
			(net "P3E_CPU0_PE1_PCH_R_RXP<14>")
		)
		(pad "2" smd rect
			(at 0 0.889 90)
			(size 0.508 0.508)
			(layers "B.Cu" "B.Mask" "B.Paste")
			(net "P3E_CPU0_PE1_PCH_RXP<14>")
		)
		(zone
			(layer "B.Cu")
			(hatch none 0.5)
			(connect_pads
				(clearance 0)
			)
			(min_thickness 0.25)
			(keepout
				(tracks not_allowed)
				(vias allowed)
				(pads allowed)
				(copperpour not_allowed)
				(footprints allowed)
			)
			(placement
				(enabled no)
				(sheetname "")
			)
			(fill
				(thermal_gap 0.5)
				(thermal_bridge_width 0.5)
				(island_removal_mode 0)
			)
			(polygon
				(pts
					(xy 349.387414 -126.091442) (xy 349.387414 -126.599442) (xy 349.768414 -126.599442) (xy 349.768414 -126.091442)
				)
			)
		)
		(zone
			(layer "B.Cu")
			(hatch none 0.5)
			(connect_pads
				(clearance 0)
			)
			(min_thickness 0.25)
			(keepout
				(tracks allowed)
				(vias not_allowed)
				(pads allowed)
				(copperpour not_allowed)
				(footprints allowed)
			)
			(placement
				(enabled no)
				(sheetname "")
			)
			(fill
				(thermal_gap 0.5)
				(thermal_bridge_width 0.5)
				(island_removal_mode 0)
			)
			(polygon
				(pts
					(xy 349.768414 -126.091442) (xy 349.768414 -126.599442) (xy 349.387414 -126.599442) (xy 349.387414 -126.091442)
				)
			)
		)
	)
)
